FILE_TYPE = MULTI_PHYS_TABLE;
PART 'CSD87384M'
{==============================================================================================================================================================}
:PACK_TYPE|MATERIAL  |PART_NUMBER= EnvComp |PART_NUMBER        |JEDEC_TYPE        |DESCRIPTION                   |CLASS  |COMPONENT_TYPE  |HEIGHT      |LPID  | SPEED_URL | Status |RPL| AML | Bus_Unit | Days;
{==============================================================================================================================================================}
'SM'     | 'IC'     | 'H66258-001'(!) = '' | 'H66258-001'      | 'LCC5_14_20_1MA' | 'IC,DS,FET N,PPAK,CSD87384M' | 'IC'  | 'LCC'          | '0.018 IN' | '3811' | 'http://speed.intel.com:8081/speed/module/pdm/item/pdm_item_detail_direct.asp?item_cde=H66258-001&item_rev=01&url_param=unused' | '' | '' | '' | '' | '' 
'SM'     | 'EMPTY'  | 'H66258-001'(!) = '' | 'H66258-001'      | 'LCC5_14_20_1MA' | 'IC,DS,FET N,PPAK,CSD87384M' | 'IO'  | 'LCC'          | '0.018 IN' | '3811' | 'http://speed.intel.com:8081/speed/module/pdm/item/pdm_item_detail_direct.asp?item_cde=H66258-001&item_rev=01&url_param=unused' | '' | '' | '' | '' | '' 
END_PART
END.
